#ISCELL
  mstr_misc dns *
  *
#ISCELL
  pure_quanta quanta_title_block_c *
  *
#ISCELL
  pure_quanta_power universal_gnd *
  page144_i100
#CELL
  pure_quanta q_res *
  page144_i101
#CELL
  pure_quanta q_res *
  page144_i102
#ISCELL
  standard offpage *
  page144_i106
#ISCELL
  standard offpage *
  page144_i107
#ISCELL
  standard offpage *
  page144_i108
#ISCELL
  standard offpage *
  page144_i109
#ISCELL
  standard offpage *
  page144_i110
#ISCELL
  standard offpage *
  page144_i111
#ISCELL
  standard offpage *
  page144_i112
#ISCELL
  standard offpage *
  page144_i113
#ISCELL
  standard offpage *
  page144_i114
#ISCELL
  standard offpage *
  page144_i115
#ISCELL
  pure_quanta_power universal_gnd *
  page144_i116
#CELL
  pure_quanta sw20s_dhnf10ftqtr *
  page144_i117
#ISCELL
  pure_quanta_power universal_gnd *
  page144_i118
#ISCELL
  standard offpage *
  page144_i119
#ISCELL
  standard offpage *
  page144_i120
#ISCELL
  standard offpage *
  page144_i121
#ISCELL
  standard offpage *
  page144_i122
#ISCELL
  standard offpage *
  page144_i123
#ISCELL
  standard offpage *
  page144_i125
#CELL
  pure_quanta q_res *
  page144_i126
#ISCELL
  pure_quanta_power universal_power *
  page144_i127
#ISCELL
  standard offpage *
  page144_i128
#CELL
  pure_quanta q_res *
  page144_i129
#ISCELL
  pure_quanta_power universal_gnd *
  page144_i130
#ISCELL
  standard offpage *
  page144_i131
#CELL
  pure_quanta q_res *
  page144_i132
#CELL
  pure_quanta q_res *
  page144_i133
#CELL
  pure_quanta q_res *
  page144_i134
#CELL
  pure_quanta q_res *
  page144_i135
#CELL
  pure_quanta sn74lvc1g07dbvr *
  page144_i136
#ISCELL
  pure_quanta_power universal_gnd *
  page144_i137
#ISCELL
  pure_quanta_power universal_power *
  page144_i138
#CELL
  pure_quanta q_cap *
  page144_i139
#ISCELL
  pure_quanta_power universal_gnd *
  page144_i140
#ISCELL
  standard offpage *
  page144_i16
#ISCELL
  pure_quanta_power universal_power *
  page144_i37
#CELL
  pure_quanta q_res *
  page144_i38
#CELL
  pure_quanta q_res *
  page144_i39
#ISCELL
  pure_quanta_power universal_power *
  page144_i40
#CELL
  pure_quanta q_res *
  page144_i41
#ISCELL
  pure_quanta_power universal_power *
  page144_i42
#ISCELL
  pure_quanta_power universal_power *
  page144_i43
#ISCELL
  pure_quanta_power universal_gnd *
  page144_i45
#CELL
  pure_quanta q_res *
  page144_i46
#ISCELL
  pure_quanta_power universal_power *
  page144_i48
#CELL
  pure_quanta q_res *
  page144_i49
#ISCELL
  standard offpage *
  page144_i52
#ISCELL
  pure_quanta_power universal_power *
  page144_i53
#ISCELL
  standard offpage *
  page144_i55
#ISCELL
  pure_quanta_power universal_gnd *
  page144_i56
#ISCELL
  standard offpage *
  page144_i57
#ISCELL
  pure_quanta_power universal_power *
  page144_i59
#CELL
  pure_quanta q_res *
  page144_i60
#ISCELL
  standard offpage *
  page144_i61
#CELL
  pure_quanta q_res *
  page144_i63
#ISCELL
  pure_quanta_power universal_power *
  page144_i64
#CELL
  pure_quanta q_res *
  page144_i66
#ISCELL
  pure_quanta_power universal_power *
  page144_i67
#ISCELL
  standard offpage *
  page144_i81
#ISCELL
  standard offpage *
  page144_i82
#ISCELL
  standard offpage *
  page144_i84
#ISCELL
  standard offpage *
  page144_i87
#CELL
  pure_quanta q_res *
  page144_i91
#ISCELL
  standard offpage *
  page144_i94
#CELL
  pure_quanta q_res *
  page144_i95
#ISCELL
  standard offpage *
  page144_i96
